# T6G (Grand Teton) — schematic netlist excerpt (pin names and nets, part order shuffled) for the footprints in the layout excerpt that follows; sources: Cadence DE-HDL packaged netlist, KiCad conversion of 04192023_DAF0TMB3IC0_F0TG_MB_C_brd_V02_OCP.brd

R1206  Q_RES  0 5% CHIP  pkg 0201LF  page 186 : A = RST_SMB_RT_ROM_R1_N ; B = FM_SMB_RT_ROM_MUX7_SEL
R2897  Q_RES  33.2 1% CHIP  pkg 0402LF  page 248 : A = SMB_1_BMC_GPU_BUF_R_SCL ; B = SMB_1_BMC_GPU_BUF_SCL
R3501  Q_RES  4.7K 5% CHIP  pkg 0402LF  page 247 : A = P3V3_OCP_SFF ; B = SMB_OCP_SFF_3V3AUX_BUF_SDA

(kicad_pcb
	(version 20260206)
	(generator "pcbnew")
	(generator_version "10.0")
	(general
		(thickness 1.6)
		(legacy_teardrops no)
	)
	(paper "A4")
	(title_block
		(title "04192023_DAF0TMB3IC0_F0TG_MB_C_brd_V02_OCP.brd")
		(comment 1 "Grand Teton / footprints 4904-4906 of 8354")
	)
	(layers
		(0 "F.Cu" signal "TOP")
		(4 "In1.Cu" signal "GND")
		(6 "In2.Cu" signal "IN1")
		(8 "In3.Cu" signal "GND1")
		(10 "In4.Cu" signal "IN2")
		(12 "In5.Cu" signal "GND2")
		(14 "In6.Cu" signal "IN3")
		(16 "In7.Cu" signal "GND3")
		(18 "In8.Cu" signal "VCC")
		(20 "In9.Cu" signal "VCC1")
		(22 "In10.Cu" signal "GND4")
		(24 "In11.Cu" signal "IN4")
		(26 "In12.Cu" signal "GND5")
		(28 "In13.Cu" signal "IN5")
		(30 "In14.Cu" signal "GND6")
		(32 "In15.Cu" signal "IN6")
		(34 "In16.Cu" signal "GND7")
		(2 "B.Cu" signal "BOTTOM")
		(9 "F.Adhes" user "F.Adhesive")
		(11 "B.Adhes" user "B.Adhesive")
		(13 "F.Paste" user "Package Geometry/Pastemask Top")
		(15 "B.Paste" user "Package Geometry/Pastemask Bottom")
		(5 "F.SilkS" user "Ref Des/Silkscreen Top")
		(7 "B.SilkS" user "Ref Des/Silkscreen Bottom")
		(1 "F.Mask" user "Board Geometry/Soldermask Top")
		(3 "B.Mask" user "Board Geometry/Soldermask Bottom")
		(17 "Dwgs.User" user "User.Drawings")
		(19 "Cmts.User" user "User.Comments")
		(21 "Eco1.User" user "User.Eco1")
		(23 "Eco2.User" user "User.Eco2")
		(25 "Edge.Cuts" user "Board Geometry/Outline")
		(27 "Margin" user)
		(31 "F.CrtYd" user "Package Geometry/Place Bound Top")
		(29 "B.CrtYd" user "Package Geometry/Place Bound Bottom")
		(35 "F.Fab" user "Ref Des/Assembly Top")
		(33 "B.Fab" user "Ref Des/Assembly Bottom")
	)
	(footprint ""
		(layer "F.Cu")
		(at 22.07768 -433.453794 180)
		(property "Reference" "R2897"
			(at 0 0 180)
			(layer "F.SilkS")
			(hide yes)
			(effects
				(font
					(size 1.27 1.27)
				)
			)
		)
		(property "Value" ""
			(at 0 0 180)
			(layer "F.Fab")
			(effects
				(font
					(size 1.27 1.27)
				)
			)
		)
		(duplicate_pad_numbers_are_jumpers no)
		(fp_line
			(start 0.7874 0.4064)
			(end -0.7874 0.4064)
			(stroke
				(width 0.1524)
				(type default)
			)
			(layer "F.SilkS")
		)
		(fp_line
			(start 0.7874 -0.4064)
			(end 0.7874 0.4064)
			(stroke
				(width 0.1524)
				(type default)
			)
			(layer "F.SilkS")
		)
		(fp_line
			(start -0.7874 0.4064)
			(end -0.7874 -0.4064)
			(stroke
				(width 0.1524)
				(type default)
			)
			(layer "F.SilkS")
		)
		(fp_line
			(start -0.7874 -0.4064)
			(end 0.7874 -0.4064)
			(stroke
				(width 0.1524)
				(type default)
			)
			(layer "F.SilkS")
		)
		(fp_line
			(start 0.67945 0.3048)
			(end 0.120396 0.3048)
			(stroke
				(width 0.1)
				(type default)
			)
			(layer "F.Fab")
		)
		(fp_line
			(start 0.67945 -0.3048)
			(end 0.67945 0.3048)
			(stroke
				(width 0.1)
				(type default)
			)
			(layer "F.Fab")
		)
		(fp_line
			(start 0.12065 -0.2794)
			(end 0.12065 -0.3048)
			(stroke
				(width 0.1)
				(type default)
			)
			(layer "F.Fab")
		)
		(fp_line
			(start 0.12065 -0.3048)
			(end 0.67945 -0.3048)
			(stroke
				(width 0.1)
				(type default)
			)
			(layer "F.Fab")
		)
		(fp_line
			(start 0.120396 0.3048)
			(end 0.120396 0.2794)
			(stroke
				(width 0.1)
				(type default)
			)
			(layer "F.Fab")
		)
		(fp_line
			(start 0.120396 0.2794)
			(end -0.12065 0.2794)
			(stroke
				(width 0.1)
				(type default)
			)
			(layer "F.Fab")
		)
		(fp_line
			(start -0.12065 0.3048)
			(end -0.67945 0.3048)
			(stroke
				(width 0.1)
				(type default)
			)
			(layer "F.Fab")
		)
		(fp_line
			(start -0.12065 0.2794)
			(end -0.12065 0.3048)
			(stroke
				(width 0.1)
				(type default)
			)
			(layer "F.Fab")
		)
		(fp_line
			(start -0.12065 -0.2794)
			(end 0.12065 -0.2794)
			(stroke
				(width 0.1)
				(type default)
			)
			(layer "F.Fab")
		)
		(fp_line
			(start -0.12065 -0.305054)
			(end -0.12065 -0.2794)
			(stroke
				(width 0.1)
				(type default)
			)
			(layer "F.Fab")
		)
		(fp_line
			(start -0.67945 0.3048)
			(end -0.67945 -0.305054)
			(stroke
				(width 0.1)
				(type default)
			)
			(layer "F.Fab")
		)
		(fp_line
			(start -0.67945 -0.305054)
			(end -0.12065 -0.305054)
			(stroke
				(width 0.1)
				(type default)
			)
			(layer "F.Fab")
		)
		(pad "1" smd circle
			(at -0.40005 0 180)
			(size 0 0)
			(layers "F.Cu" "F.Mask" "F.Paste")
			(net "SMB_1_BMC_GPU_BUF_R_SCL")
		)
		(pad "2" smd circle
			(at 0.40005 0 180)
			(size 0 0)
			(layers "F.Cu" "F.Mask" "F.Paste")
			(net "SMB_1_BMC_GPU_BUF_SCL")
		)
	)
	(footprint ""
		(layer "F.Cu")
		(at 376.809 -426.339 180)
		(property "Reference" "R1206"
			(at 0 0 180)
			(layer "F.SilkS")
			(hide yes)
			(effects
				(font
					(size 1.27 1.27)
				)
			)
		)
		(property "Value" ""
			(at 0 0 180)
			(layer "F.Fab")
			(effects
				(font
					(size 1.27 1.27)
				)
			)
		)
		(duplicate_pad_numbers_are_jumpers no)
		(fp_line
			(start 0.32512 0.175006)
			(end -0.32512 0.175006)
			(stroke
				(width 0.1)
				(type default)
			)
			(layer "F.Fab")
		)
		(fp_line
			(start 0.32512 -0.175006)
			(end 0.32512 0.175006)
			(stroke
				(width 0.1)
				(type default)
			)
			(layer "F.Fab")
		)
		(fp_line
			(start -0.32512 0.175006)
			(end -0.32512 -0.175006)
			(stroke
				(width 0.1)
				(type default)
			)
			(layer "F.Fab")
		)
		(fp_line
			(start -0.32512 -0.175006)
			(end 0.32512 -0.175006)
			(stroke
				(width 0.1)
				(type default)
			)
			(layer "F.Fab")
		)
		(pad "1" smd rect
			(at -0.2667 0 180)
			(size 0.3048 0.381)
			(layers "F.Cu" "F.Mask" "F.Paste")
			(net "RST_SMB_RT_ROM_R1_N")
		)
		(pad "2" smd rect
			(at 0.2667 0)
			(size 0.3048 0.381)
			(layers "F.Cu" "F.Mask" "F.Paste")
			(net "FM_SMB_RT_ROM_MUX7_SEL")
		)
	)
	(footprint ""
		(layer "F.Cu")
		(at 412.472886 -74.864468 180)
		(property "Reference" "R3501"
			(at 0 0 180)
			(layer "F.SilkS")
			(hide yes)
			(effects
				(font
					(size 1.27 1.27)
				)
			)
		)
		(property "Value" ""
			(at 0 0 180)
			(layer "F.Fab")
			(effects
				(font
					(size 1.27 1.27)
				)
			)
		)
		(duplicate_pad_numbers_are_jumpers no)
		(fp_line
			(start 0.7874 0.4064)
			(end -0.7874 0.4064)
			(stroke
				(width 0.1524)
				(type default)
			)
			(layer "F.SilkS")
		)
		(fp_line
			(start 0.7874 -0.4064)
			(end 0.7874 0.4064)
			(stroke
				(width 0.1524)
				(type default)
			)
			(layer "F.SilkS")
		)
		(fp_line
			(start -0.7874 0.4064)
			(end -0.7874 -0.4064)
			(stroke
				(width 0.1524)
				(type default)
			)
			(layer "F.SilkS")
		)
		(fp_line
			(start -0.7874 -0.4064)
			(end 0.7874 -0.4064)
			(stroke
				(width 0.1524)
				(type default)
			)
			(layer "F.SilkS")
		)
		(fp_line
			(start 0.67945 0.3048)
			(end 0.120396 0.3048)
			(stroke
				(width 0.1)
				(type default)
			)
			(layer "F.Fab")
		)
		(fp_line
			(start 0.67945 -0.3048)
			(end 0.67945 0.3048)
			(stroke
				(width 0.1)
				(type default)
			)
			(layer "F.Fab")
		)
		(fp_line
			(start 0.12065 -0.2794)
			(end 0.12065 -0.3048)
			(stroke
				(width 0.1)
				(type default)
			)
			(layer "F.Fab")
		)
		(fp_line
			(start 0.12065 -0.3048)
			(end 0.67945 -0.3048)
			(stroke
				(width 0.1)
				(type default)
			)
			(layer "F.Fab")
		)
		(fp_line
			(start 0.120396 0.3048)
			(end 0.120396 0.2794)
			(stroke
				(width 0.1)
				(type default)
			)
			(layer "F.Fab")
		)
		(fp_line
			(start 0.120396 0.2794)
			(end -0.12065 0.2794)
			(stroke
				(width 0.1)
				(type default)
			)
			(layer "F.Fab")
		)
		(fp_line
			(start -0.12065 0.3048)
			(end -0.67945 0.3048)
			(stroke
				(width 0.1)
				(type default)
			)
			(layer "F.Fab")
		)
		(fp_line
			(start -0.12065 0.2794)
			(end -0.12065 0.3048)
			(stroke
				(width 0.1)
				(type default)
			)
			(layer "F.Fab")
		)
		(fp_line
			(start -0.12065 -0.2794)
			(end 0.12065 -0.2794)
			(stroke
				(width 0.1)
				(type default)
			)
			(layer "F.Fab")
		)
		(fp_line
			(start -0.12065 -0.305054)
			(end -0.12065 -0.2794)
			(stroke
				(width 0.1)
				(type default)
			)
			(layer "F.Fab")
		)
		(fp_line
			(start -0.67945 0.3048)
			(end -0.67945 -0.305054)
			(stroke
				(width 0.1)
				(type default)
			)
			(layer "F.Fab")
		)
		(fp_line
			(start -0.67945 -0.305054)
			(end -0.12065 -0.305054)
			(stroke
				(width 0.1)
				(type default)
			)
			(layer "F.Fab")
		)
		(pad "1" smd circle
			(at -0.40005 0 180)
			(size 0 0)
			(layers "F.Cu" "F.Mask" "F.Paste")
			(net "P3V3_OCP_SFF")
		)
		(pad "2" smd circle
			(at 0.40005 0 180)
			(size 0 0)
			(layers "F.Cu" "F.Mask" "F.Paste")
			(net "SMB_OCP_SFF_3V3AUX_BUF_SDA")
		)
	)
)
